(kicad_pcb
	(version 20260206)
	(generator "pcbnew")
	(generator_version "10.0")
	(general
		(thickness 1.6)
		(legacy_teardrops no)
	)
	(paper "A4")
	(title_block
		(title "peb — Lightning_PEB_BRD.brd")
		(comment 1 "Lightning (Wiwynn / Facebook NVMe JBOF) / footprints 358-364 of 2563")
	)
	(layers
		(0 "F.Cu" signal "TOP")
		(4 "In1.Cu" signal "L2GND")
		(6 "In2.Cu" signal "L3")
		(8 "In3.Cu" signal "L4VCC")
		(10 "In4.Cu" signal "L5VCC")
		(12 "In5.Cu" signal "L6")
		(14 "In6.Cu" signal "L7GND")
		(2 "B.Cu" signal "BOTTOM")
		(9 "F.Adhes" user "F.Adhesive")
		(11 "B.Adhes" user "B.Adhesive")
		(13 "F.Paste" user "Package Geometry/Pastemask Top")
		(15 "B.Paste" user "Package Geometry/Pastemask Bottom")
		(5 "F.SilkS" user "Ref Des/Silkscreen Top")
		(7 "B.SilkS" user "Ref Des/Silkscreen Bottom")
		(1 "F.Mask" user "Board Geometry/Soldermask Top")
		(3 "B.Mask" user "Board Geometry/Soldermask Bottom")
		(17 "Dwgs.User" user "User.Drawings")
		(19 "Cmts.User" user "User.Comments")
		(21 "Eco1.User" user "User.Eco1")
		(23 "Eco2.User" user "User.Eco2")
		(25 "Edge.Cuts" user "Board Geometry/Outline")
		(27 "Margin" user)
		(31 "F.CrtYd" user "Package Geometry/Place Bound Top")
		(29 "B.CrtYd" user "Package Geometry/Place Bound Bottom")
		(35 "F.Fab" user "Ref Des/Assembly Top")
		(33 "B.Fab" user "Ref Des/Assembly Bottom")
	)
	(footprint ""
		(layer "F.Cu")
		(at 76.8858 -75.250548)
		(property "Reference" "R740"
			(at 0 0 0)
			(layer "F.SilkS")
			(hide yes)
			(effects
				(font
					(size 1.27 1.27)
				)
			)
		)
		(property "Value" "0R2J-2-GP"
			(at 0.064008 -3.993896 0)
			(unlocked yes)
			(layer "F.Fab")
			(hide yes)
			(effects
				(font
					(size 1.016 1.016)
					(thickness 0.1524)
				)
			)
		)
		(property "Device Type" "R402H16"
			(at 0.064008 -5.517896 0)
			(unlocked yes)
			(layer "F.Fab")
			(hide yes)
			(effects
				(font
					(size 1.016 1.016)
					(thickness 0.1524)
				)
			)
		)
		(duplicate_pad_numbers_are_jumpers no)
		(fp_line
			(start -0.508 -0.9398)
			(end -0.508 0.9398)
			(stroke
				(width 0.1524)
				(type default)
			)
			(layer "F.SilkS")
		)
		(fp_line
			(start 0.508 -0.9398)
			(end -0.508 -0.9398)
			(stroke
				(width 0.1524)
				(type default)
			)
			(layer "F.SilkS")
		)
		(fp_rect
			(start -0.508 0.9398)
			(end 0.508 -0.9398)
			(stroke
				(width 0)
				(type default)
			)
			(fill no)
			(layer "F.CrtYd")
		)
		(fp_rect
			(start -0.508 0.9398)
			(end 0.508 -0.9398)
			(stroke
				(width 0)
				(type default)
			)
			(fill no)
			(layer "F.Fab")
		)
		(pad "1" smd custom
			(at 0 -0.4445)
			(size 0.1397 0.1397)
			(layers "F.Cu" "F.Mask" "F.Paste")
			(net "ROMD2")
			(options
				(clearance outline)
				(anchor circle)
			)
			(primitives
				(gr_poly
					(pts
						(arc
							(start -0.1778 -0.2794)
							(mid -0.249642 -0.249642)
							(end -0.2794 -0.1778)
						)
						(arc
							(start -0.2794 0.1778)
							(mid -0.249642 0.249642)
							(end -0.1778 0.2794)
						)
						(arc
							(start 0.1778 0.2794)
							(mid 0.249642 0.249642)
							(end 0.2794 0.1778)
						)
						(arc
							(start 0.2794 -0.1778)
							(mid 0.249642 -0.249642)
							(end 0.1778 -0.2794)
						)
					)
					(width 0)
					(fill yes)
				)
			)
		)
		(pad "2" smd custom
			(at 0 0.4445)
			(size 0.1397 0.1397)
			(layers "F.Cu" "F.Mask" "F.Paste")
			(net "ROMD2_SEC")
			(options
				(clearance outline)
				(anchor circle)
			)
			(primitives
				(gr_poly
					(pts
						(arc
							(start -0.1778 -0.2794)
							(mid -0.249642 -0.249642)
							(end -0.2794 -0.1778)
						)
						(arc
							(start -0.2794 0.1778)
							(mid -0.249642 0.249642)
							(end -0.1778 0.2794)
						)
						(arc
							(start 0.1778 0.2794)
							(mid 0.249642 0.249642)
							(end 0.2794 0.1778)
						)
						(arc
							(start 0.2794 -0.1778)
							(mid 0.249642 -0.249642)
							(end 0.1778 -0.2794)
						)
					)
					(width 0)
					(fill yes)
				)
			)
		)
	)
	(footprint ""
		(layer "F.Cu")
		(at 227.33 -78.1304 180)
		(property "Reference" "R588"
			(at 0 0 180)
			(layer "F.SilkS")
			(hide yes)
			(effects
				(font
					(size 1.27 1.27)
				)
			)
		)
		(property "Value" "0R2J-2-GP"
			(at 0.064008 -3.993896 180)
			(unlocked yes)
			(layer "F.Fab")
			(hide yes)
			(effects
				(font
					(size 1.016 1.016)
					(thickness 0.1524)
				)
			)
		)
		(property "Device Type" "R402H16"
			(at 0.064008 -5.517896 180)
			(unlocked yes)
			(layer "F.Fab")
			(hide yes)
			(effects
				(font
					(size 1.016 1.016)
					(thickness 0.1524)
				)
			)
		)
		(duplicate_pad_numbers_are_jumpers no)
		(fp_line
			(start 0.508 -0.9398)
			(end -0.508 -0.9398)
			(stroke
				(width 0.1524)
				(type default)
			)
			(layer "F.SilkS")
		)
		(fp_line
			(start -0.508 -0.9398)
			(end -0.508 0.9398)
			(stroke
				(width 0.1524)
				(type default)
			)
			(layer "F.SilkS")
		)
		(fp_rect
			(start -0.508 0.9398)
			(end 0.508 -0.9398)
			(stroke
				(width 0)
				(type default)
			)
			(fill no)
			(layer "F.CrtYd")
		)
		(fp_rect
			(start -0.508 0.9398)
			(end 0.508 -0.9398)
			(stroke
				(width 0)
				(type default)
			)
			(fill no)
			(layer "F.Fab")
		)
		(pad "1" smd custom
			(at 0 -0.4445 180)
			(size 0.1397 0.1397)
			(layers "F.Cu" "F.Mask" "F.Paste")
			(net "BMC_I2C5_D_PEB_SCL")
			(options
				(clearance outline)
				(anchor circle)
			)
			(primitives
				(gr_poly
					(pts
						(arc
							(start -0.1778 -0.2794)
							(mid -0.249642 -0.249642)
							(end -0.2794 -0.1778)
						)
						(arc
							(start -0.2794 0.1778)
							(mid -0.249642 0.249642)
							(end -0.1778 0.2794)
						)
						(arc
							(start 0.1778 0.2794)
							(mid 0.249642 0.249642)
							(end 0.2794 0.1778)
						)
						(arc
							(start 0.2794 -0.1778)
							(mid 0.249642 -0.249642)
							(end 0.1778 -0.2794)
						)
					)
					(width 0)
					(fill yes)
				)
			)
		)
		(pad "2" smd custom
			(at 0 0.4445 180)
			(size 0.1397 0.1397)
			(layers "F.Cu" "F.Mask" "F.Paste")
			(net "TEMP_3_SCL")
			(options
				(clearance outline)
				(anchor circle)
			)
			(primitives
				(gr_poly
					(pts
						(arc
							(start -0.1778 -0.2794)
							(mid -0.249642 -0.249642)
							(end -0.2794 -0.1778)
						)
						(arc
							(start -0.2794 0.1778)
							(mid -0.249642 0.249642)
							(end -0.1778 0.2794)
						)
						(arc
							(start 0.1778 0.2794)
							(mid 0.249642 0.249642)
							(end 0.2794 0.1778)
						)
						(arc
							(start 0.2794 -0.1778)
							(mid 0.249642 -0.249642)
							(end 0.1778 -0.2794)
						)
					)
					(width 0)
					(fill yes)
				)
			)
		)
	)
	(footprint ""
		(layer "F.Cu")
		(at 80.645 -135.763 90)
		(property "Reference" "C8089"
			(at 0 0 90)
			(layer "F.SilkS")
			(hide yes)
			(effects
				(font
					(size 1.27 1.27)
				)
			)
		)
		(property "Value" "SCD1U25V2KX-2-GP"
			(at 1.1811 -2.7051 90)
			(unlocked yes)
			(layer "F.Fab")
			(hide yes)
			(effects
				(font
					(size 1.016 1.016)
					(thickness 0.1524)
				)
			)
		)
		(property "Device Type" "C402H22"
			(at 1.1811 -4.2291 90)
			(unlocked yes)
			(layer "F.Fab")
			(hide yes)
			(effects
				(font
					(size 1.016 1.016)
					(thickness 0.1524)
				)
			)
		)
		(duplicate_pad_numbers_are_jumpers no)
		(fp_rect
			(start -0.4318 0.9525)
			(end 0.4318 -0.9525)
			(stroke
				(width 0)
				(type default)
			)
			(fill no)
			(layer "F.CrtYd")
		)
		(fp_rect
			(start -0.4318 0.9525)
			(end 0.4318 -0.9525)
			(stroke
				(width 0)
				(type default)
			)
			(fill no)
			(layer "F.Fab")
		)
		(pad "1" smd custom
			(at 0 -0.4445 90)
			(size 0.1524 0.1524)
			(layers "F.Cu" "F.Mask" "F.Paste")
			(net "ADC_P1V26")
			(options
				(clearance outline)
				(anchor circle)
			)
			(primitives
				(gr_poly
					(pts
						(arc
							(start 0.3048 -0.2032)
							(mid 0.275042 -0.275042)
							(end 0.2032 -0.3048)
						)
						(arc
							(start -0.2032 -0.3048)
							(mid -0.275042 -0.275042)
							(end -0.3048 -0.2032)
						)
						(arc
							(start -0.3048 0.2032)
							(mid -0.275042 0.275042)
							(end -0.2032 0.3048)
						)
						(arc
							(start 0.2032 0.3048)
							(mid 0.275042 0.275042)
							(end 0.3048 0.2032)
						)
					)
					(width 0)
					(fill yes)
				)
			)
		)
		(pad "2" smd custom
			(at 0 0.4445 90)
			(size 0.1524 0.1524)
			(layers "F.Cu" "F.Mask" "F.Paste")
			(net "GND")
			(options
				(clearance outline)
				(anchor circle)
			)
			(primitives
				(gr_poly
					(pts
						(arc
							(start 0.3048 -0.2032)
							(mid 0.275042 -0.275042)
							(end 0.2032 -0.3048)
						)
						(arc
							(start -0.2032 -0.3048)
							(mid -0.275042 -0.275042)
							(end -0.3048 -0.2032)
						)
						(arc
							(start -0.3048 0.2032)
							(mid -0.275042 0.275042)
							(end -0.2032 0.3048)
						)
						(arc
							(start 0.2032 0.3048)
							(mid 0.275042 0.275042)
							(end 0.3048 0.2032)
						)
					)
					(width 0)
					(fill yes)
				)
			)
		)
	)
	(footprint ""
		(layer "F.Cu")
		(at 22.72919 -124.334016 90)
		(property "Reference" "C367"
			(at 0 0 90)
			(layer "F.SilkS")
			(hide yes)
			(effects
				(font
					(size 1.27 1.27)
				)
			)
		)
		(property "Value" "SCD22U10V2KX-1GP"
			(at 1.1811 -2.7051 90)
			(unlocked yes)
			(layer "F.Fab")
			(hide yes)
			(effects
				(font
					(size 1.016 1.016)
					(thickness 0.1524)
				)
			)
		)
		(property "Device Type" "C402H22"
			(at 1.1811 -4.2291 90)
			(unlocked yes)
			(layer "F.Fab")
			(hide yes)
			(effects
				(font
					(size 1.016 1.016)
					(thickness 0.1524)
				)
			)
		)
		(duplicate_pad_numbers_are_jumpers no)
		(fp_rect
			(start -0.4318 0.9525)
			(end 0.4318 -0.9525)
			(stroke
				(width 0)
				(type default)
			)
			(fill no)
			(layer "F.CrtYd")
		)
		(fp_rect
			(start -0.4318 0.9525)
			(end 0.4318 -0.9525)
			(stroke
				(width 0)
				(type default)
			)
			(fill no)
			(layer "F.Fab")
		)
		(pad "1" smd custom
			(at 0 -0.4445 90)
			(size 0.1524 0.1524)
			(layers "F.Cu" "F.Mask" "F.Paste")
			(net "PCIE_TX_CAP_P76")
			(options
				(clearance outline)
				(anchor circle)
			)
			(primitives
				(gr_poly
					(pts
						(arc
							(start 0.3048 -0.2032)
							(mid 0.275042 -0.275042)
							(end 0.2032 -0.3048)
						)
						(arc
							(start -0.2032 -0.3048)
							(mid -0.275042 -0.275042)
							(end -0.3048 -0.2032)
						)
						(arc
							(start -0.3048 0.2032)
							(mid -0.275042 0.275042)
							(end -0.2032 0.3048)
						)
						(arc
							(start 0.2032 0.3048)
							(mid 0.275042 0.275042)
							(end 0.3048 0.2032)
						)
					)
					(width 0)
					(fill yes)
				)
			)
		)
		(pad "2" smd custom
			(at 0 0.4445 90)
			(size 0.1524 0.1524)
			(layers "F.Cu" "F.Mask" "F.Paste")
			(net "PCIE_TX_P76")
			(options
				(clearance outline)
				(anchor circle)
			)
			(primitives
				(gr_poly
					(pts
						(arc
							(start 0.3048 -0.2032)
							(mid 0.275042 -0.275042)
							(end 0.2032 -0.3048)
						)
						(arc
							(start -0.2032 -0.3048)
							(mid -0.275042 -0.275042)
							(end -0.3048 -0.2032)
						)
						(arc
							(start -0.3048 0.2032)
							(mid -0.275042 0.275042)
							(end -0.2032 0.3048)
						)
						(arc
							(start 0.2032 0.3048)
							(mid 0.275042 0.275042)
							(end 0.3048 0.2032)
						)
					)
					(width 0)
					(fill yes)
				)
			)
		)
	)
	(footprint ""
		(layer "F.Cu")
		(at 16.75511 -94.083632 180)
		(property "Reference" "C41"
			(at 0 0 180)
			(layer "F.SilkS")
			(hide yes)
			(effects
				(font
					(size 1.27 1.27)
				)
			)
		)
		(property "Value" "SC1U16V3KX-5GP"
			(at 0 -2.8194 180)
			(unlocked yes)
			(layer "F.Fab")
			(hide yes)
			(effects
				(font
					(size 1.016 1.016)
					(thickness 0.1524)
				)
			)
		)
		(property "Device Type" "C603H36"
			(at 0 -4.3434 180)
			(unlocked yes)
			(layer "F.Fab")
			(hide yes)
			(effects
				(font
					(size 1.016 1.016)
					(thickness 0.1524)
				)
			)
		)
		(duplicate_pad_numbers_are_jumpers no)
		(fp_line
			(start 0.508 0)
			(end -0.508 0)
			(stroke
				(width 0.2032)
				(type default)
			)
			(layer "F.SilkS")
		)
		(fp_rect
			(start -0.5842 1.3335)
			(end 0.5842 -1.3335)
			(stroke
				(width 0)
				(type default)
			)
			(fill no)
			(layer "F.CrtYd")
		)
		(fp_rect
			(start -0.5842 1.3335)
			(end 0.5842 -1.3335)
			(stroke
				(width 0)
				(type default)
			)
			(fill no)
			(layer "F.Fab")
		)
		(pad "1" smd custom
			(at 0 -0.762 180)
			(size 0.2159 0.2159)
			(layers "F.Cu" "F.Mask" "F.Paste")
			(net "BMC_TPM_RST")
			(options
				(clearance outline)
				(anchor circle)
			)
			(primitives
				(gr_poly
					(pts
						(arc
							(start -0.3302 -0.4318)
							(mid -0.402042 -0.402042)
							(end -0.4318 -0.3302)
						)
						(arc
							(start -0.4318 0.3302)
							(mid -0.402042 0.402042)
							(end -0.3302 0.4318)
						)
						(arc
							(start 0.3302 0.4318)
							(mid 0.402042 0.402042)
							(end 0.4318 0.3302)
						)
						(arc
							(start 0.4318 -0.3302)
							(mid 0.402042 -0.402042)
							(end 0.3302 -0.4318)
						)
					)
					(width 0)
					(fill yes)
				)
			)
		)
		(pad "2" smd custom
			(at 0 0.762 180)
			(size 0.2159 0.2159)
			(layers "F.Cu" "F.Mask" "F.Paste")
			(net "Q20_G")
			(options
				(clearance outline)
				(anchor circle)
			)
			(primitives
				(gr_poly
					(pts
						(arc
							(start -0.3302 -0.4318)
							(mid -0.402042 -0.402042)
							(end -0.4318 -0.3302)
						)
						(arc
							(start -0.4318 0.3302)
							(mid -0.402042 0.402042)
							(end -0.3302 0.4318)
						)
						(arc
							(start 0.3302 0.4318)
							(mid 0.402042 0.402042)
							(end 0.4318 0.3302)
						)
						(arc
							(start 0.4318 -0.3302)
							(mid 0.402042 -0.402042)
							(end 0.3302 -0.4318)
						)
					)
					(width 0)
					(fill yes)
				)
			)
		)
	)
	(footprint ""
		(layer "F.Cu")
		(at 27.4447 -33.89884 180)
		(property "Reference" "R540"
			(at 0 0 180)
			(layer "F.SilkS")
			(hide yes)
			(effects
				(font
					(size 1.27 1.27)
				)
			)
		)
		(property "Value" "0R2J-2-GP"
			(at 0.064008 -3.993896 180)
			(unlocked yes)
			(layer "F.Fab")
			(hide yes)
			(effects
				(font
					(size 1.016 1.016)
					(thickness 0.1524)
				)
			)
		)
		(property "Device Type" "R402H16"
			(at 0.064008 -5.517896 180)
			(unlocked yes)
			(layer "F.Fab")
			(hide yes)
			(effects
				(font
					(size 1.016 1.016)
					(thickness 0.1524)
				)
			)
		)
		(duplicate_pad_numbers_are_jumpers no)
		(fp_line
			(start 0.508 -0.9398)
			(end -0.508 -0.9398)
			(stroke
				(width 0.1524)
				(type default)
			)
			(layer "F.SilkS")
		)
		(fp_line
			(start -0.508 -0.9398)
			(end -0.508 0.9398)
			(stroke
				(width 0.1524)
				(type default)
			)
			(layer "F.SilkS")
		)
		(fp_rect
			(start -0.508 0.9398)
			(end 0.508 -0.9398)
			(stroke
				(width 0)
				(type default)
			)
			(fill no)
			(layer "F.CrtYd")
		)
		(fp_rect
			(start -0.508 0.9398)
			(end 0.508 -0.9398)
			(stroke
				(width 0)
				(type default)
			)
			(fill no)
			(layer "F.Fab")
		)
		(pad "1" smd custom
			(at 0 -0.4445 180)
			(size 0.1397 0.1397)
			(layers "F.Cu" "F.Mask" "F.Paste")
			(net "LED_MDI0_100M_N")
			(options
				(clearance outline)
				(anchor circle)
			)
			(primitives
				(gr_poly
					(pts
						(arc
							(start -0.1778 -0.2794)
							(mid -0.249642 -0.249642)
							(end -0.2794 -0.1778)
						)
						(arc
							(start -0.2794 0.1778)
							(mid -0.249642 0.249642)
							(end -0.1778 0.2794)
						)
						(arc
							(start 0.1778 0.2794)
							(mid 0.249642 0.249642)
							(end 0.2794 0.1778)
						)
						(arc
							(start 0.2794 -0.1778)
							(mid 0.249642 -0.249642)
							(end 0.1778 -0.2794)
						)
					)
					(width 0)
					(fill yes)
				)
			)
		)
		(pad "2" smd custom
			(at 0 0.4445 180)
			(size 0.1397 0.1397)
			(layers "F.Cu" "F.Mask" "F.Paste")
			(net "LED_MDI0_100M_N_R")
			(options
				(clearance outline)
				(anchor circle)
			)
			(primitives
				(gr_poly
					(pts
						(arc
							(start -0.1778 -0.2794)
							(mid -0.249642 -0.249642)
							(end -0.2794 -0.1778)
						)
						(arc
							(start -0.2794 0.1778)
							(mid -0.249642 0.249642)
							(end -0.1778 0.2794)
						)
						(arc
							(start 0.1778 0.2794)
							(mid 0.249642 0.249642)
							(end 0.2794 0.1778)
						)
						(arc
							(start 0.2794 -0.1778)
							(mid 0.249642 -0.249642)
							(end 0.1778 -0.2794)
						)
					)
					(width 0)
					(fill yes)
				)
			)
		)
	)
	(footprint ""
		(layer "F.Cu")
		(at 126.976124 -196.443092)
		(property "Reference" "R7938"
			(at 0 0 0)
			(layer "F.SilkS")
			(hide yes)
			(effects
				(font
					(size 1.27 1.27)
				)
			)
		)
		(property "Value" "0R2J-2-GP"
			(at 0.064008 -3.993896 0)
			(unlocked yes)
			(layer "F.Fab")
			(hide yes)
			(effects
				(font
					(size 1.016 1.016)
					(thickness 0.1524)
				)
			)
		)
		(property "Device Type" "R402H16"
			(at 0.064008 -5.517896 0)
			(unlocked yes)
			(layer "F.Fab")
			(hide yes)
			(effects
				(font
					(size 1.016 1.016)
					(thickness 0.1524)
				)
			)
		)
		(duplicate_pad_numbers_are_jumpers no)
		(fp_line
			(start -0.508 -0.9398)
			(end -0.508 0.9398)
			(stroke
				(width 0.1524)
				(type default)
			)
			(layer "F.SilkS")
		)
		(fp_line
			(start 0.508 -0.9398)
			(end -0.508 -0.9398)
			(stroke
				(width 0.1524)
				(type default)
			)
			(layer "F.SilkS")
		)
		(fp_rect
			(start -0.508 0.9398)
			(end 0.508 -0.9398)
			(stroke
				(width 0)
				(type default)
			)
			(fill no)
			(layer "F.CrtYd")
		)
		(fp_rect
			(start -0.508 0.9398)
			(end 0.508 -0.9398)
			(stroke
				(width 0)
				(type default)
			)
			(fill no)
			(layer "F.Fab")
		)
		(pad "1" smd custom
			(at 0 -0.4445)
			(size 0.1397 0.1397)
			(layers "F.Cu" "F.Mask" "F.Paste")
			(net "SSD_ATNLED#1")
			(options
				(clearance outline)
				(anchor circle)
			)
			(primitives
				(gr_poly
					(pts
						(arc
							(start -0.1778 -0.2794)
							(mid -0.249642 -0.249642)
							(end -0.2794 -0.1778)
						)
						(arc
							(start -0.2794 0.1778)
							(mid -0.249642 0.249642)
							(end -0.1778 0.2794)
						)
						(arc
							(start 0.1778 0.2794)
							(mid 0.249642 0.249642)
							(end 0.2794 0.1778)
						)
						(arc
							(start 0.2794 -0.1778)
							(mid 0.249642 -0.249642)
							(end 0.1778 -0.2794)
						)
					)
					(width 0)
					(fill yes)
				)
			)
		)
		(pad "2" smd custom
			(at 0 0.4445)
			(size 0.1397 0.1397)
			(layers "F.Cu" "F.Mask" "F.Paste")
			(net "SSD_ATNLED#1_R")
			(options
				(clearance outline)
				(anchor circle)
			)
			(primitives
				(gr_poly
					(pts
						(arc
							(start -0.1778 -0.2794)
							(mid -0.249642 -0.249642)
							(end -0.2794 -0.1778)
						)
						(arc
							(start -0.2794 0.1778)
							(mid -0.249642 0.249642)
							(end -0.1778 0.2794)
						)
						(arc
							(start 0.1778 0.2794)
							(mid 0.249642 0.249642)
							(end 0.2794 0.1778)
						)
						(arc
							(start 0.2794 -0.1778)
							(mid 0.249642 -0.249642)
							(end 0.1778 -0.2794)
						)
					)
					(width 0)
					(fill yes)
				)
			)
		)
	)
)
